(kicad_pcb
	(version 20240108)
	(generator "pcbnew")
	(generator_version "8.0")
	(general
		(thickness 1.62)
		(legacy_teardrops no)
	)
	(paper "A4")
	(title_block
		(title "Jetson Orin Baseboard")
		(date "2025-03-12")
		(rev "1.3.4")
		(company "Antmicro Ltd")
		(comment 1 "www.antmicro.com")
		(comment 9 "footprints 579-584 of 677")
	)
	(layers
		(0 "F.Cu" signal)
		(1 "In1.Cu" signal)
		(2 "In2.Cu" signal)
		(3 "In3.Cu" signal)
		(4 "In4.Cu" jumper)
		(5 "In5.Cu" signal)
		(6 "In6.Cu" signal)
		(31 "B.Cu" signal)
		(32 "B.Adhes" user "B.Adhesive")
		(33 "F.Adhes" user "F.Adhesive")
		(34 "B.Paste" user)
		(35 "F.Paste" user)
		(36 "B.SilkS" user "B.Silkscreen")
		(37 "F.SilkS" user "F.Silkscreen")
		(38 "B.Mask" user)
		(39 "F.Mask" user)
		(40 "Dwgs.User" user "User.Drawings")
		(41 "Cmts.User" user "User.Comments")
		(42 "Eco1.User" user "User.Eco1")
		(43 "Eco2.User" user "User.Eco2")
		(44 "Edge.Cuts" user)
		(45 "Margin" user)
		(46 "B.CrtYd" user "B.Courtyard")
		(47 "F.CrtYd" user "F.Courtyard")
		(48 "B.Fab" user)
		(49 "F.Fab" user)
	)
	(footprint "antmicro-footprints:C_1206_3216Metric"
		(layer "B.Cu")
		(at 31.5 77.75 90)
		(descr "Capacitor SMD 1206")
		(tags "capacitor SMD 1206")
		(property "Reference" "C84"
			(at 1.15 2.05 -90)
			(layer "B.SilkS")
			(effects
				(font
					(size 0.7 0.7)
					(thickness 0.15)
				)
				(justify left bottom mirror)
			)
		)
		(property "Value" "C_47u_16V_1206"
			(at 0 -2.1 -90)
			(layer "B.Fab")
			(effects
				(font
					(size 0.7 0.7)
					(thickness 0.15)
				)
				(justify left bottom mirror)
			)
		)
		(property "Footprint" "antmicro-footprints:C_1206_3216Metric"
			(at 0 0 90)
			(layer "F.Fab")
			(hide yes)
			(effects
				(font
					(size 1.27 1.27)
					(thickness 0.15)
				)
			)
		)
		(property "Datasheet" "https://product.tdk.com/en/search/capacitor/ceramic/mlcc/info?part_no=C3216X5R1C476M160AB"
			(at 0 0 90)
			(layer "F.Fab")
			(hide yes)
			(effects
				(font
					(size 1.27 1.27)
					(thickness 0.15)
				)
			)
		)
		(property "Author" "Antmicro"
			(at 109.25 46.25 0)
			(layer "B.Fab")
			(hide yes)
			(effects
				(font
					(size 1 1)
					(thickness 0.15)
				)
				(justify mirror)
			)
		)
		(property "Dielectric" "X5R"
			(at 109.25 46.25 0)
			(layer "B.Fab")
			(hide yes)
			(effects
				(font
					(size 1 1)
					(thickness 0.15)
				)
				(justify mirror)
			)
		)
		(property "License" "Apache-2.0"
			(at 109.25 46.25 0)
			(layer "B.Fab")
			(hide yes)
			(effects
				(font
					(size 1 1)
					(thickness 0.15)
				)
				(justify mirror)
			)
		)
		(property "MPN" "C3216X5R1C476M160AB"
			(at 109.25 46.25 0)
			(layer "B.Fab")
			(hide yes)
			(effects
				(font
					(size 1 1)
					(thickness 0.15)
				)
				(justify mirror)
			)
		)
		(property "Manufacturer" "TDK"
			(at 109.25 46.25 0)
			(layer "B.Fab")
			(hide yes)
			(effects
				(font
					(size 1 1)
					(thickness 0.15)
				)
				(justify mirror)
			)
		)
		(property "Public" "False"
			(at 109.25 46.25 0)
			(layer "B.Fab")
			(hide yes)
			(effects
				(font
					(size 1 1)
					(thickness 0.15)
				)
				(justify mirror)
			)
		)
		(property "Val" "47u"
			(at 109.25 46.25 0)
			(layer "B.Fab")
			(hide yes)
			(effects
				(font
					(size 1 1)
					(thickness 0.15)
				)
				(justify mirror)
			)
		)
		(property "Voltage" "16V"
			(at 109.25 46.25 0)
			(layer "B.Fab")
			(hide yes)
			(effects
				(font
					(size 1 1)
					(thickness 0.15)
				)
				(justify mirror)
			)
		)
		(sheetname "Ethernet")
		(sheetfile "ethernet.kicad_sch")
		(attr smd)
		(fp_line
			(start -0.8 -0.901)
			(end 0.8 -0.901)
			(stroke
				(width 0.15)
				(type solid)
			)
			(layer "B.SilkS")
		)
		(fp_line
			(start -0.8 0.899)
			(end 0.8 0.899)
			(stroke
				(width 0.15)
				(type solid)
			)
			(layer "B.SilkS")
		)
		(fp_rect
			(start -2.325 1.15)
			(end 2.325 -1.15)
			(stroke
				(width 0.05)
				(type default)
			)
			(fill none)
			(layer "B.CrtYd")
		)
		(fp_rect
			(start -1.6 0.799)
			(end 1.6 -0.801)
			(stroke
				(width 0.15)
				(type solid)
			)
			(fill none)
			(layer "B.Fab")
		)
		(fp_text user "Author: Antmicro"
			(at -2.8 -5.6 -90)
			(layer "B.Fab")
			(hide yes)
			(effects
				(font
					(size 0.7 0.7)
					(thickness 0.15)
				)
				(justify left bottom mirror)
			)
		)
		(fp_text user "License: Apache-2.0"
			(at -2.8 -6.6 -90)
			(layer "B.Fab")
			(hide yes)
			(effects
				(font
					(size 0.7 0.7)
					(thickness 0.15)
				)
				(justify left bottom mirror)
			)
		)
		(fp_text user "${REFERENCE}"
			(at -2.8 -4.6 -90)
			(layer "B.Fab")
			(hide yes)
			(effects
				(font
					(size 0.7 0.7)
					(thickness 0.15)
				)
				(justify left bottom mirror)
			)
		)
		(pad "1" smd roundrect
			(at -1.5 -0.001 90)
			(size 1.15 1.8)
			(layers "B.Cu" "B.Paste" "B.Mask")
			(roundrect_rratio 0.25)
			(net 1 "GND")
			(pintype "passive")
		)
		(pad "2" smd roundrect
			(at 1.5 -0.001 90)
			(size 1.15 1.8)
			(layers "B.Cu" "B.Paste" "B.Mask")
			(roundrect_rratio 0.25)
			(net 500 "POE_OUTPUT")
			(pintype "passive")
		)
	)
	(footprint "antmicro-footprints:R_0603_1608Metric"
		(layer "B.Cu")
		(at 39.8 69.8)
		(descr "Resistor SMD 0603")
		(tags "resistor SMD 0603")
		(property "Reference" "R243"
			(at 0.4 0.65 -90)
			(layer "B.SilkS")
			(effects
				(font
					(size 0.7 0.7)
					(thickness 0.15)
				)
				(justify left bottom mirror)
			)
		)
		(property "Value" "R_0R_0603"
			(at 0 -1.6 180)
			(layer "B.Fab")
			(effects
				(font
					(size 0.7 0.7)
					(thickness 0.15)
				)
				(justify left bottom mirror)
			)
		)
		(property "Footprint" "antmicro-footprints:R_0603_1608Metric"
			(at 0 0 0)
			(layer "F.Fab")
			(hide yes)
			(effects
				(font
					(size 1.27 1.27)
					(thickness 0.15)
				)
			)
		)
		(property "Datasheet" "https://www.bourns.com/docs/product-datasheets/cr.pdf?sfvrsn=574d41f6_14"
			(at 0 0 0)
			(layer "F.Fab")
			(hide yes)
			(effects
				(font
					(size 1.27 1.27)
					(thickness 0.15)
				)
			)
		)
		(property "Author" "Antmicro"
			(at 0 0 0)
			(layer "B.Fab")
			(hide yes)
			(effects
				(font
					(size 1 1)
					(thickness 0.15)
				)
				(justify mirror)
			)
		)
		(property "Current" "1A"
			(at 0 0 0)
			(layer "B.Fab")
			(hide yes)
			(effects
				(font
					(size 1 1)
					(thickness 0.15)
				)
				(justify mirror)
			)
		)
		(property "License" "Apache-2.0"
			(at 0 0 0)
			(layer "B.Fab")
			(hide yes)
			(effects
				(font
					(size 1 1)
					(thickness 0.15)
				)
				(justify mirror)
			)
		)
		(property "MPN" "CR0603-J/-000ELF"
			(at 0 0 0)
			(layer "B.Fab")
			(hide yes)
			(effects
				(font
					(size 1 1)
					(thickness 0.15)
				)
				(justify mirror)
			)
		)
		(property "Manufacturer" "Bourns"
			(at 0 0 0)
			(layer "B.Fab")
			(hide yes)
			(effects
				(font
					(size 1 1)
					(thickness 0.15)
				)
				(justify mirror)
			)
		)
		(property "Tolerance" ""
			(at 0 0 0)
			(layer "B.Fab")
			(hide yes)
			(effects
				(font
					(size 1 1)
					(thickness 0.15)
				)
				(justify mirror)
			)
		)
		(property "Val" "0R"
			(at 0 0 0)
			(layer "B.Fab")
			(hide yes)
			(effects
				(font
					(size 1 1)
					(thickness 0.15)
				)
				(justify mirror)
			)
		)
		(sheetname "Ethernet")
		(sheetfile "ethernet.kicad_sch")
		(attr smd exclude_from_pos_files exclude_from_bom dnp)
		(fp_line
			(start 0.15 -0.4)
			(end -0.15 -0.4)
			(stroke
				(width 0.15)
				(type solid)
			)
			(layer "B.SilkS")
		)
		(fp_line
			(start 0.15 0.4)
			(end -0.15 0.4)
			(stroke
				(width 0.15)
				(type solid)
			)
			(layer "B.SilkS")
		)
		(fp_rect
			(start -1.25 0.65)
			(end 1.25 -0.65)
			(stroke
				(width 0.05)
				(type solid)
			)
			(fill none)
			(layer "B.CrtYd")
		)
		(fp_rect
			(start -0.8 0.4)
			(end 0.8 -0.4)
			(stroke
				(width 0.15)
				(type solid)
			)
			(fill none)
			(layer "B.Fab")
		)
		(fp_text user "Author: Antmicro"
			(at -1.25 -4.9 180)
			(layer "B.Fab")
			(hide yes)
			(effects
				(font
					(size 0.7 0.7)
					(thickness 0.15)
				)
				(justify left bottom mirror)
			)
		)
		(fp_text user "${REFERENCE}"
			(at -1.25 -3.898 180)
			(layer "B.Fab")
			(hide yes)
			(effects
				(font
					(size 0.7 0.7)
					(thickness 0.15)
				)
				(justify left bottom mirror)
			)
		)
		(fp_text user "License: Apache-2.0"
			(at -1.25 -5.9 180)
			(layer "B.Fab")
			(hide yes)
			(effects
				(font
					(size 0.7 0.7)
					(thickness 0.15)
				)
				(justify left bottom mirror)
			)
		)
		(pad "1" smd roundrect
			(at -0.7 0)
			(size 0.8 1)
			(layers "B.Cu" "B.Paste" "B.Mask")
			(roundrect_rratio 0.2)
			(net 500 "POE_OUTPUT")
			(pintype "passive")
		)
		(pad "2" smd roundrect
			(at 0.7 0)
			(size 0.8 1)
			(layers "B.Cu" "B.Paste" "B.Mask")
			(roundrect_rratio 0.2)
			(net 683 "Net-(U23-TRIM)")
			(pintype "passive")
		)
	)
	(footprint "antmicro-footprints:R_0402_1005Metric"
		(layer "B.Cu")
		(at 68.6 94.4 -90)
		(descr "Resistor SMD 0402")
		(tags "resistor SMD 0402")
		(property "Reference" "R130"
			(at -1.15 -2.41 90)
			(layer "B.SilkS")
			(effects
				(font
					(size 0.7 0.7)
					(thickness 0.15)
				)
				(justify left bottom mirror)
			)
		)
		(property "Value" "R_4k7_0402"
			(at 0 -1.4 90)
			(layer "B.Fab")
			(effects
				(font
					(size 0.7 0.7)
					(thickness 0.15)
				)
				(justify left bottom mirror)
			)
		)
		(property "Footprint" "antmicro-footprints:R_0402_1005Metric"
			(at 0 0 -90)
			(layer "F.Fab")
			(hide yes)
			(effects
				(font
					(size 1.27 1.27)
					(thickness 0.15)
				)
			)
		)
		(property "Datasheet" "https://www.bourns.com/docs/product-datasheets/cr.pdf"
			(at 0 0 -90)
			(layer "F.Fab")
			(hide yes)
			(effects
				(font
					(size 1.27 1.27)
					(thickness 0.15)
				)
			)
		)
		(property "Author" "Antmicro"
			(at -25.8 163 0)
			(layer "B.Fab")
			(hide yes)
			(effects
				(font
					(size 1 1)
					(thickness 0.15)
				)
				(justify mirror)
			)
		)
		(property "License" "Apache-2.0"
			(at -25.8 163 0)
			(layer "B.Fab")
			(hide yes)
			(effects
				(font
					(size 1 1)
					(thickness 0.15)
				)
				(justify mirror)
			)
		)
		(property "MPN" "CR0402-FX-4701GLF"
			(at -25.8 163 0)
			(layer "B.Fab")
			(hide yes)
			(effects
				(font
					(size 1 1)
					(thickness 0.15)
				)
				(justify mirror)
			)
		)
		(property "Manufacturer" "Bourns"
			(at -25.8 163 0)
			(layer "B.Fab")
			(hide yes)
			(effects
				(font
					(size 1 1)
					(thickness 0.15)
				)
				(justify mirror)
			)
		)
		(property "Tolerance" "1%"
			(at -25.8 163 0)
			(layer "B.Fab")
			(hide yes)
			(effects
				(font
					(size 1 1)
					(thickness 0.15)
				)
				(justify mirror)
			)
		)
		(property "Val" "4k7"
			(at -25.8 163 0)
			(layer "B.Fab")
			(hide yes)
			(effects
				(font
					(size 1 1)
					(thickness 0.15)
				)
				(justify mirror)
			)
		)
		(sheetname "USB Debug, DP")
		(sheetfile "usb.kicad_sch")
		(attr smd)
		(fp_rect
			(start -0.925 0.47)
			(end 0.925 -0.47)
			(stroke
				(width 0.05)
				(type default)
			)
			(fill none)
			(layer "B.CrtYd")
		)
		(fp_rect
			(start -0.5 0.25)
			(end 0.5 -0.25)
			(stroke
				(width 0.15)
				(type solid)
			)
			(fill none)
			(layer "B.Fab")
		)
		(fp_text user "License: Apache-2.0"
			(at -0.95 -5.169 90)
			(layer "B.Fab")
			(hide yes)
			(effects
				(font
					(size 0.7 0.7)
					(thickness 0.15)
				)
				(justify left bottom mirror)
			)
		)
		(fp_text user "${REFERENCE}"
			(at -0.95 -3.168 90)
			(layer "B.Fab")
			(hide yes)
			(effects
				(font
					(size 0.7 0.7)
					(thickness 0.15)
				)
				(justify left bottom mirror)
			)
		)
		(fp_text user "Author: Antmicro"
			(at -0.95 -4.169 90)
			(layer "B.Fab")
			(hide yes)
			(effects
				(font
					(size 0.7 0.7)
					(thickness 0.15)
				)
				(justify left bottom mirror)
			)
		)
		(pad "1" smd roundrect
			(at -0.48 0 270)
			(size 0.59 0.64)
			(layers "B.Cu" "B.Paste" "B.Mask")
			(roundrect_rratio 0.25)
			(net 87 "+3V3")
			(pintype "passive")
		)
		(pad "2" smd roundrect
			(at 0.48 0 270)
			(size 0.59 0.64)
			(layers "B.Cu" "B.Paste" "B.Mask")
			(roundrect_rratio 0.25)
			(net 395 "/USB Debug, DP/PDC_I2C2_SCL")
			(pintype "passive")
		)
	)
	(footprint "antmicro-footprints:R_0402_1005Metric"
		(layer "B.Cu")
		(at 89 112.6 -90)
		(descr "Resistor SMD 0402")
		(tags "resistor SMD 0402")
		(property "Reference" "R219"
			(at -0.965 3.55 90)
			(layer "B.SilkS")
			(effects
				(font
					(size 0.7 0.7)
					(thickness 0.15)
				)
				(justify left bottom mirror)
			)
		)
		(property "Value" "R_10k_0402"
			(at 0 -1.4 90)
			(layer "B.Fab")
			(effects
				(font
					(size 0.7 0.7)
					(thickness 0.15)
				)
				(justify left bottom mirror)
			)
		)
		(property "Footprint" "antmicro-footprints:R_0402_1005Metric"
			(at 0 0 -90)
			(layer "F.Fab")
			(hide yes)
			(effects
				(font
					(size 1.27 1.27)
					(thickness 0.15)
				)
			)
		)
		(property "Datasheet" "https://www.bourns.com/docs/product-datasheets/cr.pdf"
			(at 0 0 -90)
			(layer "F.Fab")
			(hide yes)
			(effects
				(font
					(size 1.27 1.27)
					(thickness 0.15)
				)
			)
		)
		(property "Author" "Antmicro"
			(at -23.6 201.6 0)
			(layer "B.Fab")
			(hide yes)
			(effects
				(font
					(size 1 1)
					(thickness 0.15)
				)
				(justify mirror)
			)
		)
		(property "License" "Apache-2.0"
			(at -23.6 201.6 0)
			(layer "B.Fab")
			(hide yes)
			(effects
				(font
					(size 1 1)
					(thickness 0.15)
				)
				(justify mirror)
			)
		)
		(property "MPN" "CR0402-FX-1002GLF"
			(at -23.6 201.6 0)
			(layer "B.Fab")
			(hide yes)
			(effects
				(font
					(size 1 1)
					(thickness 0.15)
				)
				(justify mirror)
			)
		)
		(property "Manufacturer" "Bourns"
			(at -23.6 201.6 0)
			(layer "B.Fab")
			(hide yes)
			(effects
				(font
					(size 1 1)
					(thickness 0.15)
				)
				(justify mirror)
			)
		)
		(property "Tolerance" "1%"
			(at -23.6 201.6 0)
			(layer "B.Fab")
			(hide yes)
			(effects
				(font
					(size 1 1)
					(thickness 0.15)
				)
				(justify mirror)
			)
		)
		(property "Val" "10k"
			(at -23.6 201.6 0)
			(layer "B.Fab")
			(hide yes)
			(effects
				(font
					(size 1 1)
					(thickness 0.15)
				)
				(justify mirror)
			)
		)
		(sheetname "Peripherals")
		(sheetfile "peripherals.kicad_sch")
		(attr smd)
		(fp_rect
			(start -0.925 0.47)
			(end 0.925 -0.47)
			(stroke
				(width 0.05)
				(type default)
			)
			(fill none)
			(layer "B.CrtYd")
		)
		(fp_rect
			(start -0.5 0.25)
			(end 0.5 -0.25)
			(stroke
				(width 0.15)
				(type solid)
			)
			(fill none)
			(layer "B.Fab")
		)
		(fp_text user "License: Apache-2.0"
			(at -0.95 -5.169 90)
			(layer "B.Fab")
			(hide yes)
			(effects
				(font
					(size 0.7 0.7)
					(thickness 0.15)
				)
				(justify left bottom mirror)
			)
		)
		(fp_text user "${REFERENCE}"
			(at -0.95 -3.168 90)
			(layer "B.Fab")
			(hide yes)
			(effects
				(font
					(size 0.7 0.7)
					(thickness 0.15)
				)
				(justify left bottom mirror)
			)
		)
		(fp_text user "Author: Antmicro"
			(at -0.95 -4.169 90)
			(layer "B.Fab")
			(hide yes)
			(effects
				(font
					(size 0.7 0.7)
					(thickness 0.15)
				)
				(justify left bottom mirror)
			)
		)
		(pad "1" smd roundrect
			(at -0.48 0 270)
			(size 0.59 0.64)
			(layers "B.Cu" "B.Paste" "B.Mask")
			(roundrect_rratio 0.25)
			(net 281 "~{GPIO_INT}")
			(pintype "passive")
		)
		(pad "2" smd roundrect
			(at 0.48 0 270)
			(size 0.59 0.64)
			(layers "B.Cu" "B.Paste" "B.Mask")
			(roundrect_rratio 0.25)
			(net 112 "+1V8")
			(pintype "passive")
		)
	)
	(footprint "antmicro-footprints:TP_SMD_0.75mm"
		(layer "B.Cu")
		(at 89.7492 114.4 -90)
		(property "Reference" "TP56"
			(at -0.855 1.4042 90)
			(layer "B.SilkS")
			(effects
				(font
					(size 0.7 0.7)
					(thickness 0.15)
				)
				(justify left bottom mirror)
			)
		)
		(property "Value" "TP_0.75mm_SMD"
			(at 0 -1.2 90)
			(layer "B.Fab")
			(effects
				(font
					(size 0.7 0.7)
					(thickness 0.15)
				)
				(justify left bottom mirror)
			)
		)
		(property "Footprint" "antmicro-footprints:TP_SMD_0.75mm"
			(at 0 0 -90)
			(layer "F.Fab")
			(hide yes)
			(effects
				(font
					(size 1.27 1.27)
					(thickness 0.15)
				)
			)
		)
		(property "Author" "Antmicro"
			(at -24.6508 204.1492 0)
			(layer "B.Fab")
			(hide yes)
			(effects
				(font
					(size 1 1)
					(thickness 0.15)
				)
				(justify mirror)
			)
		)
		(property "License" "Apache-2.0"
			(at -24.6508 204.1492 0)
			(layer "B.Fab")
			(hide yes)
			(effects
				(font
					(size 1 1)
					(thickness 0.15)
				)
				(justify mirror)
			)
		)
		(property "MPN" ""
			(at -24.6508 204.1492 0)
			(layer "B.Fab")
			(hide yes)
			(effects
				(font
					(size 1 1)
					(thickness 0.15)
				)
				(justify mirror)
			)
		)
		(property "Manufacturer" ""
			(at -24.6508 204.1492 0)
			(layer "B.Fab")
			(hide yes)
			(effects
				(font
					(size 1 1)
					(thickness 0.15)
				)
				(justify mirror)
			)
		)
		(sheetname "HDMI")
		(sheetfile "hdmi.kicad_sch")
		(attr exclude_from_pos_files exclude_from_bom)
		(fp_circle
			(center 0 0)
			(end 0.475 0)
			(stroke
				(width 0.05)
				(type default)
			)
			(fill none)
			(layer "B.CrtYd")
		)
		(fp_text user "${REFERENCE}"
			(at -0.4 -2.7 90)
			(layer "B.Fab")
			(hide yes)
			(effects
				(font
					(size 0.7 0.7)
					(thickness 0.15)
				)
				(justify left bottom mirror)
			)
		)
		(fp_text user "License: Apache-2.0"
			(at -0.4 -5.101 90)
			(layer "B.Fab")
			(hide yes)
			(effects
				(font
					(size 0.7 0.7)
					(thickness 0.15)
				)
				(justify left bottom mirror)
			)
		)
		(fp_text user "Author: Antmicro"
			(at -0.4 -3.901 90)
			(layer "B.Fab")
			(hide yes)
			(effects
				(font
					(size 0.7 0.7)
					(thickness 0.15)
				)
				(justify left bottom mirror)
			)
		)
		(pad "1" smd circle
			(at 0 0 270)
			(size 0.75 0.75)
			(layers "B.Cu" "B.Mask")
			(net 701 "/HDMI/HDMI_SDA_3V3")
			(pinfunction "1")
			(pintype "passive")
		)
	)
	(footprint "antmicro-footprints:TP_SMD_0.75mm"
		(layer "B.Cu")
		(at 63.205 70.17 180)
		(property "Reference" "TP33"
			(at -3.165 -0.39 0)
			(layer "B.SilkS")
			(effects
				(font
					(size 0.7 0.7)
					(thickness 0.15)
				)
				(justify left bottom mirror)
			)
		)
		(property "Value" "TP_0.75mm_SMD"
			(at 0 -1.2 0)
			(layer "B.Fab")
			(effects
				(font
					(size 0.7 0.7)
					(thickness 0.15)
				)
				(justify left bottom mirror)
			)
		)
		(property "Footprint" "antmicro-footprints:TP_SMD_0.75mm"
			(at 0 0 180)
			(layer "F.Fab")
			(hide yes)
			(effects
				(font
					(size 1.27 1.27)
					(thickness 0.15)
				)
			)
		)
		(property "Author" "Antmicro"
			(at 126.41 140.34 0)
			(layer "B.Fab")
			(hide yes)
			(effects
				(font
					(size 1 1)
					(thickness 0.15)
				)
				(justify mirror)
			)
		)
		(property "License" "Apache-2.0"
			(at 126.41 140.34 0)
			(layer "B.Fab")
			(hide yes)
			(effects
				(font
					(size 1 1)
					(thickness 0.15)
				)
				(justify mirror)
			)
		)
		(property "MPN" ""
			(at 126.41 140.34 0)
			(layer "B.Fab")
			(hide yes)
			(effects
				(font
					(size 1 1)
					(thickness 0.15)
				)
				(justify mirror)
			)
		)
		(property "Manufacturer" ""
			(at 126.41 140.34 0)
			(layer "B.Fab")
			(hide yes)
			(effects
				(font
					(size 1 1)
					(thickness 0.15)
				)
				(justify mirror)
			)
		)
		(sheetname "Supply")
		(sheetfile "supply.kicad_sch")
		(attr exclude_from_pos_files exclude_from_bom)
		(fp_circle
			(center 0 0)
			(end 0.475 0)
			(stroke
				(width 0.05)
				(type default)
			)
			(fill none)
			(layer "B.CrtYd")
		)
		(fp_text user "Author: Antmicro"
			(at -0.4 -3.901 0)
			(layer "B.Fab")
			(hide yes)
			(effects
				(font
					(size 0.7 0.7)
					(thickness 0.15)
				)
				(justify left bottom mirror)
			)
		)
		(fp_text user "${REFERENCE}"
			(at -0.4 -2.7 0)
			(layer "B.Fab")
			(hide yes)
			(effects
				(font
					(size 0.7 0.7)
					(thickness 0.15)
				)
				(justify left bottom mirror)
			)
		)
		(fp_text user "License: Apache-2.0"
			(at -0.4 -5.101 0)
			(layer "B.Fab")
			(hide yes)
			(effects
				(font
					(size 0.7 0.7)
					(thickness 0.15)
				)
				(justify left bottom mirror)
			)
		)
		(pad "1" smd circle
			(at 0 0 180)
			(size 0.75 0.75)
			(layers "B.Cu" "B.Mask")
			(net 86 "~{RESET}")
			(pinfunction "1")
			(pintype "passive")
		)
	)
)
